# S9S_MB_2U (Grand Teton) — schematic netlist excerpt (pin names and nets, part order shuffled) for the footprints in the layout excerpt that follows; sources: Cadence DE-HDL packaged netlist, KiCad conversion of 03242023_DA0F0TMBIJ0_F0T_Motherboard_J_brd_V01_OCP.brd

J17  SCONN288_ADR50017P130CC  SCONN288_ADR50017-P130CC IO  pkg DDR288S_1-1VXB  page 98
  VIN_BULK0  = P12V_S3_AUX_CPU1_NVDIMM
  RFU0  = TP_CHA_CPU1_DIMM1_FRU_0
  VIN_MGMT  = P3V3_AUX
  HSCL  = I3C_SPD_DDRABCD_CPU1_LVC1_SCL_R
  HSDA  = I3C_SPD_DDRABCD_CPU1_LVC1_SDA
  VSS0  = GND
  DQ0_A  = M_A_CPU1_SA_DQ<0>
  VSS1  = GND
  DQ1_A  = M_A_CPU1_SA_DQ<1>
  VSS2  = GND
  DQS0_A_T  = M_A_CPU1_SA_DQS_DP<0>
  DQS0_A_C  = M_A_CPU1_SA_DQS_DN<0>
  VSS3  = GND
  DQ4_A  = M_A_CPU1_SA_DQ<4>
  VSS4  = GND
  DQ5_A  = M_A_CPU1_SA_DQ<5>
  VSS5  = GND
  DQ8_A  = M_A_CPU1_SA_DQ<8>
  VSS6  = GND
  DQ9_A  = M_A_CPU1_SA_DQ<9>
  VSS7  = GND
  DQS1_A_T  = M_A_CPU1_SA_DQS_DP<1>
  DQS1_A_C  = M_A_CPU1_SA_DQS_DN<1>
  VSS8  = GND
  DQ12_A  = M_A_CPU1_SA_DQ<12>
  VSS9  = GND
  DQ13_A  = M_A_CPU1_SA_DQ<13>
  VSS10  = GND
  DQ16_A  = M_A_CPU1_SA_DQ<16>
  VSS11  = GND
  DQ17_A  = M_A_CPU1_SA_DQ<17>
  VSS12  = GND
  DQS2_A_T  = M_A_CPU1_SA_DQS_DP<2>
  DQS2_A_C  = M_A_CPU1_SA_DQS_DN<2>
  VSS13  = GND
  DQ20_A  = M_A_CPU1_SA_DQ<20>
  VSS14  = GND
  DQ21_A  = M_A_CPU1_SA_DQ<21>
  VSS15  = GND
  DQ24_A  = M_A_CPU1_SA_DQ<24>
  VSS16  = GND
  DQ25_A  = M_A_CPU1_SA_DQ<25>
  VSS17  = GND
  DQS3_A_T  = M_A_CPU1_SA_DQS_DP<3>
  DQS3_A_C  = M_A_CPU1_SA_DQS_DN<3>
  VSS18  = GND
  DQ28_A  = M_A_CPU1_SA_DQ<28>
  VSS19  = GND
  DQ29_A  = M_A_CPU1_SA_DQ<29>
  VSS20  = GND
  CB0_A  = M_A_CPU1_SA_CB<0>
  VSS21  = GND
  CB1_A  = M_A_CPU1_SA_CB<1>
  VSS22  = GND
  DQS4_A_T  = M_A_CPU1_SA_DQS_DP<4>
  DQS4_A_C  = M_A_CPU1_SA_DQS_DN<4>
  VSS23  = GND
  CB4_A  = M_A_CPU1_SA_CB<4>
  VSS24  = GND
  CB5_A  = M_A_CPU1_SA_CB<5>
  VSS25  = GND
  ALERT_N  = M_A_CPU1_ALERT_N
  VSS26  = GND
  CS0_A_N  = M_A_CPU1_SA_CS_N<0>
  VSS27  = GND
  CA0_A  = M_A_CPU1_SA_CA<0>
  VSS28  = GND
  CA2_A  = M_A_CPU1_SA_CA<2>
  VSS29  = GND
  CA4_A  = M_A_CPU1_SA_CA<4>
  VSS30  = GND
  CA6_A  = M_A_CPU1_SA_CA<6>
  VSS31  = GND
  PAR_A  = M_A_CPU1_SA_PAR
  VSS32  = GND
  CA0_B  = M_A_CPU1_SB_CA<0>
  VSS33  = GND
  CA2_B  = M_A_CPU1_SB_CA<2>
  VSS34  = GND
  CA4_B  = M_A_CPU1_SB_CA<4>
  VSS35  = GND
  CA6_B  = M_A_CPU1_SB_CA<6>
  VSS36  = GND
  CS0_B_N  = M_A_CPU1_SB_CS_N<0>
  VSS37  = GND
  \lbd||rsp_a_n\  = M_A_CPU1_SA_RSP<0>
  \lbs||rsp_b_n\  = M_A_CPU1_SB_RSP<0>
  VSS38  = GND
  CB4_B  = M_A_CPU1_SB_CB<4>
  VSS39  = GND
  CB5_B  = M_A_CPU1_SB_CB<5>
  VSS40  = GND
  \dqs9_b_t||tdqs9_b_t||dbi4_b_n\  = M_A_CPU1_SB_DQS_DP<9>
  \dqs9_b_c||tdqs9_b_c\  = M_A_CPU1_SB_DQS_DN<9>
  VSS41  = GND
  CB0_B  = M_A_CPU1_SB_CB<0>
  VSS42  = GND
  CB1_B  = M_A_CPU1_SB_CB<1>
  VSS43  = GND
  DQ0_B  = M_A_CPU1_SB_DQ<0>
  VSS44  = GND
  DQ1_B  = M_A_CPU1_SB_DQ<1>
  VSS45  = GND
  DQS0_B_T  = M_A_CPU1_SB_DQS_DP<0>
  DQS0_B_C  = M_A_CPU1_SB_DQS_DN<0>
  VSS46  = GND
  DQ4_B  = M_A_CPU1_SB_DQ<4>
  VSS47  = GND
  DQ5_B  = M_A_CPU1_SB_DQ<5>
  VSS48  = GND
  DQ8_B  = M_A_CPU1_SB_DQ<8>
  VSS49  = GND
  DQ9_B  = M_A_CPU1_SB_DQ<9>
  VSS50  = GND
  DQS1_B_T  = M_A_CPU1_SB_DQS_DP<1>
  DQS1_B_C  = M_A_CPU1_SB_DQS_DN<1>
  VSS51  = GND
  DQ12_B  = M_A_CPU1_SB_DQ<12>
  VSS52  = GND
  DQ13_B  = M_A_CPU1_SB_DQ<13>
  VSS53  = GND
  DQ16_B  = M_A_CPU1_SB_DQ<16>
  VSS54  = GND
  DQ17_B  = M_A_CPU1_SB_DQ<17>
  VSS55  = GND
  DQS2_B_T  = M_A_CPU1_SB_DQS_DP<2>
  DQS2_B_C  = M_A_CPU1_SB_DQS_DN<2>
  VSS56  = GND
  DQ20_B  = M_A_CPU1_SB_DQ<20>
  VSS57  = GND
  DQ21_B  = M_A_CPU1_SB_DQ<21>
  VSS58  = GND
  DQ24_B  = M_A_CPU1_SB_DQ<24>
  VSS59  = GND
  DQ25_B  = M_A_CPU1_SB_DQ<25>
  VSS60  = GND
  DQS3_B_T  = M_A_CPU1_SB_DQS_DP<3>
  DQS3_B_C  = M_A_CPU1_SB_DQS_DN<3>
  VSS61  = GND
  DQ28_B  = M_A_CPU1_SB_DQ<28>
  VSS62  = GND
  DQ29_B  = M_A_CPU1_SB_DQ<29>
  VSS63  = GND
  RFU1  = TP_CHA_CPU1_DIMM1_FRU_1
  VIN_BULK1  = P12V_S3_AUX_CPU1_NVDIMM
  VIN_BULK2  = P12V_S3_AUX_CPU1_NVDIMM
  \pwr_good||fail_n\  = PWRGD_CHA_CPU1_DIMM1
  HSA  = PD_CHA_CPU1_DIMM1_SAA
  RFU2  = TP_CHA_CPU1_DIMM1_FRU_2
  RFU3  = TP_CHA_CPU1_DIMM1_FRU_3
  VSS64  = GND
  DQ2_A  = M_A_CPU1_SA_DQ<2>
  VSS65  = GND
  DQ3_A  = M_A_CPU1_SA_DQ<3>
  VSS66  = GND
  \dqs5_a_c||tdqs5_a_c||dqs5_a_t||tdqs5_a_t\  = M_A_CPU1_SA_DQS_DN<5>
  \dqs5_a_t||tdqs5_a_t\  = M_A_CPU1_SA_DQS_DP<5>
  VSS67  = GND
  DQ6_A  = M_A_CPU1_SA_DQ<6>
  VSS68  = GND
  DQ7_A  = M_A_CPU1_SA_DQ<7>
  VSS69  = GND
  DQ10_A  = M_A_CPU1_SA_DQ<10>
  VSS70  = GND
  DQ11_A  = M_A_CPU1_SA_DQ<11>
  VSS71  = GND
  \dqs6_a_c||tdqs6_a_c||dqs6_a_t||tdqs6_a_t\  = M_A_CPU1_SA_DQS_DN<6>
  \dqs6_a_t||tdqs6_a_t\  = M_A_CPU1_SA_DQS_DP<6>
  VSS72  = GND
  DQ14_A  = M_A_CPU1_SA_DQ<14>
  VSS73  = GND
  DQ15_A  = M_A_CPU1_SA_DQ<15>
  VSS74  = GND
  DQ18_A  = M_A_CPU1_SA_DQ<18>
  VSS75  = GND
  DQ19_A  = M_A_CPU1_SA_DQ<19>
  VSS76  = GND
  \dqs7_a_c||tdqs7_a_c\  = M_A_CPU1_SA_DQS_DN<7>
  \dqs7_a_t||tdqs7_a_t\  = M_A_CPU1_SA_DQS_DP<7>
  VSS77  = GND
  DQ22_A  = M_A_CPU1_SA_DQ<22>
  VSS78  = GND
  DQ23_A  = M_A_CPU1_SA_DQ<23>
  VSS79  = GND
  DQ26_A  = M_A_CPU1_SA_DQ<26>
  VSS80  = GND
  DQ27_A  = M_A_CPU1_SA_DQ<27>
  VSS81  = GND
  \dqs8_a_c||tdqs8_a_c\  = M_A_CPU1_SA_DQS_DN<8>
  \dqs8_a_t||tdqs8_a_t\  = M_A_CPU1_SA_DQS_DP<8>
  VSS82  = GND
  DQ30_A  = M_A_CPU1_SA_DQ<30>
  VSS83  = GND
  DQ31_A  = M_A_CPU1_SA_DQ<31>
  VSS84  = GND
  CB2_A  = M_A_CPU1_SA_CB<2>
  VSS85  = GND
  CB3_A  = M_A_CPU1_SA_CB<3>
  VSS86  = GND
  \dqs9_a_c||tdqs9_a_c\  = M_A_CPU1_SA_DQS_DN<9>
  \dqs9_a_t||tdqs9_a_t\  = M_A_CPU1_SA_DQS_DP<9>
  VSS87  = GND
  CB6_A  = M_A_CPU1_SA_CB<6>
  VSS88  = GND
  CB7_A  = M_A_CPU1_SA_CB<7>
  VSS89  = GND
  RESET_N  = RST_M_AB_CPU1_FPGA_N
  VSS90  = GND
  CS1_A_N  = M_A_CPU1_SA_CS_N<1>
  VSS91  = GND
  CA1_A  = M_A_CPU1_SA_CA<1>
  VSS92  = GND
  CA3_A  = M_A_CPU1_SA_CA<3>
  VSS93  = GND
  CA5_A  = M_A_CPU1_SA_CA<5>
  VSS94  = GND
  CK_T  = M_A_CPU1_CLK_DP<0>
  CK_C  = M_A_CPU1_CLK_DN<0>
  VSS95  = GND
  RFU4  = TP_CHA_CPU1_DIMM1_FRU_4
  CA1_B  = M_A_CPU1_SB_CA<1>
  VSS96  = GND
  CA3_B  = M_A_CPU1_SB_CA<3>
  VSS97  = GND
  CA5_B  = M_A_CPU1_SB_CA<5>
  VSS98  = GND
  PAR_B  = M_A_CPU1_SB_PAR
  VSS99  = GND
  CS1_B_N  = M_A_CPU1_SB_CS_N<1>
  VSS100  = GND
  RFU5  = TP_CHA_CPU1_DIMM1_FRU_5
  RFU6  = TP_CHA_CPU1_DIMM1_FRU_6
  VSS101  = GND
  CB6_B  = M_A_CPU1_SB_CB<6>
  VSS102  = GND
  CB7_B  = M_A_CPU1_SB_CB<7>
  VSS103  = GND
  DQS4_B_C  = M_A_CPU1_SB_DQS_DN<4>
  DQS4_B_T  = M_A_CPU1_SB_DQS_DP<4>
  VSS104  = GND
  CB2_B  = M_A_CPU1_SB_CB<2>
  VSS105  = GND
  CB3_B  = M_A_CPU1_SB_CB<3>
  VSS106  = GND
  DQ2_B  = M_A_CPU1_SB_DQ<2>
  VSS107  = GND
  DQ3_B  = M_A_CPU1_SB_DQ<3>
  VSS108  = GND
  \dqs5_b_c||tdqs5_b_c\  = M_A_CPU1_SB_DQS_DN<5>
  \dqs5_b_t||tdqs5_b_t\  = M_A_CPU1_SB_DQS_DP<5>
  VSS109  = GND
  DQ6_B  = M_A_CPU1_SB_DQ<6>
  VSS110  = GND
  DQ7_B  = M_A_CPU1_SB_DQ<7>
  VSS111  = GND
  DQ10_B  = M_A_CPU1_SB_DQ<10>
  VSS112  = GND
  DQ11_B  = M_A_CPU1_SB_DQ<11>
  VSS113  = GND
  \dqs6_b_c||tdqs6_b_c\  = M_A_CPU1_SB_DQS_DN<6>
  \dqs6_b_t||tdqs6_b_t\  = M_A_CPU1_SB_DQS_DP<6>
  VSS114  = GND
  DQ14_B  = M_A_CPU1_SB_DQ<14>
  VSS115  = GND
  DQ15_B  = M_A_CPU1_SB_DQ<15>
  VSS116  = GND
  DQ18_B  = M_A_CPU1_SB_DQ<18>
  VSS117  = GND
  DQ19_B  = M_A_CPU1_SB_DQ<19>
  VSS118  = GND
  \dqs7_b_c||tdqs7_b_c\  = M_A_CPU1_SB_DQS_DN<7>
  \dqs7_b_t||tdqs7_b_t\  = M_A_CPU1_SB_DQS_DP<7>
  VSS119  = GND
  DQ22_B  = M_A_CPU1_SB_DQ<22>
  VSS120  = GND
  DQ23_B  = M_A_CPU1_SB_DQ<23>
  VSS121  = GND
  DQ26_B  = M_A_CPU1_SB_DQ<26>
  VSS122  = GND
  DQ27_B  = M_A_CPU1_SB_DQ<27>
  VSS123  = GND
  \dqs8_b_c||tdqs8_b_c\  = M_A_CPU1_SB_DQS_DN<8>
  \dqs8_b_t||tdqs8_b_t\  = M_A_CPU1_SB_DQS_DP<8>
  VSS124  = GND
  DQ30_B  = M_A_CPU1_SB_DQ<30>
  VSS125  = GND
  DQ31_B  = M_A_CPU1_SB_DQ<31>
  VSS126  = GND
  G1  = GND
  G2  = GND
  G3  = GND

(kicad_pcb
	(version 20260206)
	(generator "pcbnew")
	(generator_version "10.0")
	(general
		(thickness 1.6)
		(legacy_teardrops no)
	)
	(paper "A4")
	(title_block
		(title "03242023_DA0F0TMBIJ0_F0T_Motherboard_J_brd_V01_OCP.brd")
		(comment 1 "Grand Teton / footprint 1335 of 6105 (J17), pads 138-182 of 291")
	)
	(layers
		(0 "F.Cu" signal "TOP")
		(4 "In1.Cu" signal "GND")
		(6 "In2.Cu" signal "IN1")
		(8 "In3.Cu" signal "GND1")
		(10 "In4.Cu" signal "IN2")
		(12 "In5.Cu" signal "GND2")
		(14 "In6.Cu" signal "IN3")
		(16 "In7.Cu" signal "GND3")
		(18 "In8.Cu" signal "VCC")
		(20 "In9.Cu" signal "VCC1")
		(22 "In10.Cu" signal "GND4")
		(24 "In11.Cu" signal "IN4")
		(26 "In12.Cu" signal "GND5")
		(28 "In13.Cu" signal "IN5")
		(30 "In14.Cu" signal "GND6")
		(32 "In15.Cu" signal "IN6")
		(34 "In16.Cu" signal "GND7")
		(2 "B.Cu" signal "BOTTOM")
		(9 "F.Adhes" user "F.Adhesive")
		(11 "B.Adhes" user "B.Adhesive")
		(13 "F.Paste" user "Package Geometry/Pastemask Top")
		(15 "B.Paste" user "Package Geometry/Pastemask Bottom")
		(5 "F.SilkS" user "Ref Des/Silkscreen Top")
		(7 "B.SilkS" user "Ref Des/Silkscreen Bottom")
		(1 "F.Mask" user "Board Geometry/Soldermask Top")
		(3 "B.Mask" user "Board Geometry/Soldermask Bottom")
		(17 "Dwgs.User" user "User.Drawings")
		(19 "Cmts.User" user "User.Comments")
		(21 "Eco1.User" user "User.Eco1")
		(23 "Eco2.User" user "User.Eco2")
		(25 "Edge.Cuts" user "Board Geometry/Outline")
		(27 "Margin" user)
		(31 "F.CrtYd" user "Package Geometry/Place Bound Top")
		(29 "B.CrtYd" user "Package Geometry/Place Bound Bottom")
		(35 "F.Fab" user "Ref Des/Assembly Top")
		(33 "B.Fab" user "Ref Des/Assembly Bottom")
	)
	(footprint ""
		(layer "F.Cu")
		(at 55.45328 -258.091686)
		(property "Reference" "J17"
			(at -0.178562 -81.717134 0)
			(unlocked yes)
			(layer "F.SilkS")
			(effects
				(font
					(size 0.7874 0.5842)
					(thickness 0.1524)
				)
				(justify left)
			)
		)
		(property "Value" ""
			(at 0 0 0)
			(layer "F.Fab")
			(effects
				(font
					(size 1.27 1.27)
				)
			)
		)
		(duplicate_pad_numbers_are_jumpers no)
		(pad "138" smd rect
			(at -2.050034 58.224928 270)
			(size 0.519938 1.4986)
			(layers "F.Cu" "F.Mask" "F.Paste")
			(net "M_A_CPU1_SB_DQS_DN<3>")
		)
		(pad "139" smd rect
			(at -2.050034 59.075066 270)
			(size 0.519938 1.4986)
			(layers "F.Cu" "F.Mask" "F.Paste")
			(net "GND")
		)
		(pad "140" smd rect
			(at -2.050034 59.92495 270)
			(size 0.519938 1.4986)
			(layers "F.Cu" "F.Mask" "F.Paste")
			(net "M_A_CPU1_SB_DQ<28>")
		)
		(pad "141" smd rect
			(at -2.050034 60.775088 270)
			(size 0.519938 1.4986)
			(layers "F.Cu" "F.Mask" "F.Paste")
			(net "GND")
		)
		(pad "142" smd rect
			(at -2.050034 61.624972 270)
			(size 0.519938 1.4986)
			(layers "F.Cu" "F.Mask" "F.Paste")
			(net "M_A_CPU1_SB_DQ<29>")
		)
		(pad "143" smd rect
			(at -2.050034 62.47511 270)
			(size 0.519938 1.4986)
			(layers "F.Cu" "F.Mask" "F.Paste")
			(net "GND")
		)
		(pad "144" smd rect
			(at -2.050034 63.324994 270)
			(size 0.519938 1.4986)
			(layers "F.Cu" "F.Mask" "F.Paste")
			(net "TP_CHA_CPU1_DIMM1_FRU_1")
		)
		(pad "145" smd rect
			(at 2.050034 -63.324994 270)
			(size 0.519938 1.4986)
			(layers "F.Cu" "F.Mask" "F.Paste")
			(net "P12V_S3_AUX_CPU1_NVDIMM")
		)
		(pad "146" smd rect
			(at 2.050034 -62.47511 270)
			(size 0.519938 1.4986)
			(layers "F.Cu" "F.Mask" "F.Paste")
			(net "P12V_S3_AUX_CPU1_NVDIMM")
		)
		(pad "147" smd rect
			(at 2.050034 -61.624972 270)
			(size 0.519938 1.4986)
			(layers "F.Cu" "F.Mask" "F.Paste")
			(net "PWRGD_CHA_CPU1_DIMM1")
		)
		(pad "148" smd rect
			(at 2.050034 -60.775088 270)
			(size 0.519938 1.4986)
			(layers "F.Cu" "F.Mask" "F.Paste")
			(net "PD_CHA_CPU1_DIMM1_SAA")
		)
		(pad "149" smd rect
			(at 2.050034 -59.92495 270)
			(size 0.519938 1.4986)
			(layers "F.Cu" "F.Mask" "F.Paste")
			(net "TP_CHA_CPU1_DIMM1_FRU_2")
		)
		(pad "150" smd rect
			(at 2.050034 -59.075066 270)
			(size 0.519938 1.4986)
			(layers "F.Cu" "F.Mask" "F.Paste")
			(net "TP_CHA_CPU1_DIMM1_FRU_3")
		)
		(pad "151" smd rect
			(at 2.050034 -58.224928 270)
			(size 0.519938 1.4986)
			(layers "F.Cu" "F.Mask" "F.Paste")
			(net "GND")
		)
		(pad "152" smd rect
			(at 2.050034 -57.375044 270)
			(size 0.519938 1.4986)
			(layers "F.Cu" "F.Mask" "F.Paste")
			(net "M_A_CPU1_SA_DQ<2>")
		)
		(pad "153" smd rect
			(at 2.050034 -56.524906 270)
			(size 0.519938 1.4986)
			(layers "F.Cu" "F.Mask" "F.Paste")
			(net "GND")
		)
		(pad "154" smd rect
			(at 2.050034 -55.675022 270)
			(size 0.519938 1.4986)
			(layers "F.Cu" "F.Mask" "F.Paste")
			(net "M_A_CPU1_SA_DQ<3>")
		)
		(pad "155" smd rect
			(at 2.050034 -54.824884 270)
			(size 0.519938 1.4986)
			(layers "F.Cu" "F.Mask" "F.Paste")
			(net "GND")
		)
		(pad "156" smd rect
			(at 2.050034 -53.975 270)
			(size 0.519938 1.4986)
			(layers "F.Cu" "F.Mask" "F.Paste")
			(net "M_A_CPU1_SA_DQS_DN<5>")
		)
		(pad "157" smd rect
			(at 2.050034 -53.125116 270)
			(size 0.519938 1.4986)
			(layers "F.Cu" "F.Mask" "F.Paste")
			(net "M_A_CPU1_SA_DQS_DP<5>")
		)
		(pad "158" smd rect
			(at 2.050034 -52.274978 270)
			(size 0.519938 1.4986)
			(layers "F.Cu" "F.Mask" "F.Paste")
			(net "GND")
		)
		(pad "159" smd rect
			(at 2.050034 -51.425094 270)
			(size 0.519938 1.4986)
			(layers "F.Cu" "F.Mask" "F.Paste")
			(net "M_A_CPU1_SA_DQ<6>")
		)
		(pad "160" smd rect
			(at 2.050034 -50.574956 270)
			(size 0.519938 1.4986)
			(layers "F.Cu" "F.Mask" "F.Paste")
			(net "GND")
		)
		(pad "161" smd rect
			(at 2.050034 -49.725072 270)
			(size 0.519938 1.4986)
			(layers "F.Cu" "F.Mask" "F.Paste")
			(net "M_A_CPU1_SA_DQ<7>")
		)
		(pad "162" smd rect
			(at 2.050034 -48.874934 270)
			(size 0.519938 1.4986)
			(layers "F.Cu" "F.Mask" "F.Paste")
			(net "GND")
		)
		(pad "163" smd rect
			(at 2.050034 -48.02505 270)
			(size 0.519938 1.4986)
			(layers "F.Cu" "F.Mask" "F.Paste")
			(net "M_A_CPU1_SA_DQ<10>")
		)
		(pad "164" smd rect
			(at 2.050034 -47.174912 270)
			(size 0.519938 1.4986)
			(layers "F.Cu" "F.Mask" "F.Paste")
			(net "GND")
		)
		(pad "165" smd rect
			(at 2.050034 -46.325028 270)
			(size 0.519938 1.4986)
			(layers "F.Cu" "F.Mask" "F.Paste")
			(net "M_A_CPU1_SA_DQ<11>")
		)
		(pad "166" smd rect
			(at 2.050034 -45.47489 270)
			(size 0.519938 1.4986)
			(layers "F.Cu" "F.Mask" "F.Paste")
			(net "GND")
		)
		(pad "167" smd rect
			(at 2.050034 -44.625006 270)
			(size 0.519938 1.4986)
			(layers "F.Cu" "F.Mask" "F.Paste")
			(net "M_A_CPU1_SA_DQS_DN<6>")
		)
		(pad "168" smd rect
			(at 2.050034 -43.775122 270)
			(size 0.519938 1.4986)
			(layers "F.Cu" "F.Mask" "F.Paste")
			(net "M_A_CPU1_SA_DQS_DP<6>")
		)
		(pad "169" smd rect
			(at 2.050034 -42.924984 270)
			(size 0.519938 1.4986)
			(layers "F.Cu" "F.Mask" "F.Paste")
			(net "GND")
		)
		(pad "170" smd rect
			(at 2.050034 -42.0751 270)
			(size 0.519938 1.4986)
			(layers "F.Cu" "F.Mask" "F.Paste")
			(net "M_A_CPU1_SA_DQ<14>")
		)
		(pad "171" smd rect
			(at 2.050034 -41.224962 270)
			(size 0.519938 1.4986)
			(layers "F.Cu" "F.Mask" "F.Paste")
			(net "GND")
		)
		(pad "172" smd rect
			(at 2.050034 -40.375078 270)
			(size 0.519938 1.4986)
			(layers "F.Cu" "F.Mask" "F.Paste")
			(net "M_A_CPU1_SA_DQ<15>")
		)
		(pad "173" smd rect
			(at 2.050034 -39.52494 270)
			(size 0.519938 1.4986)
			(layers "F.Cu" "F.Mask" "F.Paste")
			(net "GND")
		)
		(pad "174" smd rect
			(at 2.050034 -38.675056 270)
			(size 0.519938 1.4986)
			(layers "F.Cu" "F.Mask" "F.Paste")
			(net "M_A_CPU1_SA_DQ<18>")
		)
		(pad "175" smd rect
			(at 2.050034 -37.824918 270)
			(size 0.519938 1.4986)
			(layers "F.Cu" "F.Mask" "F.Paste")
			(net "GND")
		)
		(pad "176" smd rect
			(at 2.050034 -36.975034 270)
			(size 0.519938 1.4986)
			(layers "F.Cu" "F.Mask" "F.Paste")
			(net "M_A_CPU1_SA_DQ<19>")
		)
		(pad "177" smd rect
			(at 2.050034 -36.124896 270)
			(size 0.519938 1.4986)
			(layers "F.Cu" "F.Mask" "F.Paste")
			(net "GND")
		)
		(pad "178" smd rect
			(at 2.050034 -35.275012 270)
			(size 0.519938 1.4986)
			(layers "F.Cu" "F.Mask" "F.Paste")
			(net "M_A_CPU1_SA_DQS_DN<7>")
		)
		(pad "179" smd rect
			(at 2.050034 -34.425128 270)
			(size 0.519938 1.4986)
			(layers "F.Cu" "F.Mask" "F.Paste")
			(net "M_A_CPU1_SA_DQS_DP<7>")
		)
		(pad "180" smd rect
			(at 2.050034 -33.57499 270)
			(size 0.519938 1.4986)
			(layers "F.Cu" "F.Mask" "F.Paste")
			(net "GND")
		)
		(pad "181" smd rect
			(at 2.050034 -32.725106 270)
			(size 0.519938 1.4986)
			(layers "F.Cu" "F.Mask" "F.Paste")
			(net "M_A_CPU1_SA_DQ<22>")
		)
		(pad "182" smd rect
			(at 2.050034 -31.874968 270)
			(size 0.519938 1.4986)
			(layers "F.Cu" "F.Mask" "F.Paste")
			(net "GND")
		)
	)
)
